# T6G (Grand Teton) — schematic netlist excerpt (pin names and nets, part order shuffled) for the footprints in the layout excerpt that follows; sources: Cadence DE-HDL packaged netlist, KiCad conversion of 04192023_DAF0TMB3IC0_F0TG_MB_C_brd_V02_OCP.brd

PC6607  Q_CAP  470PF 50V 10% X7R  pkg 0402  page 362 : A = P0V9_RETIMER_CPU0_TEMP0 ; B = GND
C1061  Q_CAP  0.1UF 25V 10% X7R  pkg 0402  page 142 : A = P3V3_AUX ; B = GND
R6709  Q_RES  0 5% CHIP  pkg 0201LF  page 320 : A = RST_RT_CPU1_P0_RESET_N ; B = RST_RT_CPU1_P0_RESET_R_N

(kicad_pcb
	(version 20260206)
	(generator "pcbnew")
	(generator_version "10.0")
	(general
		(thickness 1.6)
		(legacy_teardrops no)
	)
	(paper "A4")
	(title_block
		(title "04192023_DAF0TMB3IC0_F0TG_MB_C_brd_V02_OCP.brd")
		(comment 1 "Grand Teton / footprints 4227-4229 of 8354")
	)
	(layers
		(0 "F.Cu" signal "TOP")
		(4 "In1.Cu" signal "GND")
		(6 "In2.Cu" signal "IN1")
		(8 "In3.Cu" signal "GND1")
		(10 "In4.Cu" signal "IN2")
		(12 "In5.Cu" signal "GND2")
		(14 "In6.Cu" signal "IN3")
		(16 "In7.Cu" signal "GND3")
		(18 "In8.Cu" signal "VCC")
		(20 "In9.Cu" signal "VCC1")
		(22 "In10.Cu" signal "GND4")
		(24 "In11.Cu" signal "IN4")
		(26 "In12.Cu" signal "GND5")
		(28 "In13.Cu" signal "IN5")
		(30 "In14.Cu" signal "GND6")
		(32 "In15.Cu" signal "IN6")
		(34 "In16.Cu" signal "GND7")
		(2 "B.Cu" signal "BOTTOM")
		(9 "F.Adhes" user "F.Adhesive")
		(11 "B.Adhes" user "B.Adhesive")
		(13 "F.Paste" user "Package Geometry/Pastemask Top")
		(15 "B.Paste" user "Package Geometry/Pastemask Bottom")
		(5 "F.SilkS" user "Ref Des/Silkscreen Top")
		(7 "B.SilkS" user "Ref Des/Silkscreen Bottom")
		(1 "F.Mask" user "Board Geometry/Soldermask Top")
		(3 "B.Mask" user "Board Geometry/Soldermask Bottom")
		(17 "Dwgs.User" user "User.Drawings")
		(19 "Cmts.User" user "User.Comments")
		(21 "Eco1.User" user "User.Eco1")
		(23 "Eco2.User" user "User.Eco2")
		(25 "Edge.Cuts" user "Board Geometry/Outline")
		(27 "Margin" user)
		(31 "F.CrtYd" user "Package Geometry/Place Bound Top")
		(29 "B.CrtYd" user "Package Geometry/Place Bound Bottom")
		(35 "F.Fab" user "Ref Des/Assembly Top")
		(33 "B.Fab" user "Ref Des/Assembly Bottom")
	)
	(footprint ""
		(layer "F.Cu")
		(at 99.822 -79.121)
		(property "Reference" "C1061"
			(at 0 0 0)
			(layer "F.SilkS")
			(hide yes)
			(effects
				(font
					(size 1.27 1.27)
				)
			)
		)
		(property "Value" ""
			(at 0 0 0)
			(layer "F.Fab")
			(effects
				(font
					(size 1.27 1.27)
				)
			)
		)
		(duplicate_pad_numbers_are_jumpers no)
		(fp_line
			(start -0.7874 -0.4064)
			(end 0.7874 -0.4064)
			(stroke
				(width 0.1524)
				(type default)
			)
			(layer "F.SilkS")
		)
		(fp_line
			(start -0.7874 0.4064)
			(end -0.7874 -0.4064)
			(stroke
				(width 0.1524)
				(type default)
			)
			(layer "F.SilkS")
		)
		(fp_line
			(start 0.7874 -0.4064)
			(end 0.7874 0.4064)
			(stroke
				(width 0.1524)
				(type default)
			)
			(layer "F.SilkS")
		)
		(fp_line
			(start 0.7874 0.4064)
			(end -0.7874 0.4064)
			(stroke
				(width 0.1524)
				(type default)
			)
			(layer "F.SilkS")
		)
		(fp_line
			(start -0.67945 -0.305054)
			(end -0.12065 -0.305054)
			(stroke
				(width 0.1)
				(type default)
			)
			(layer "F.Fab")
		)
		(fp_line
			(start -0.67945 0.3048)
			(end -0.67945 -0.305054)
			(stroke
				(width 0.1)
				(type default)
			)
			(layer "F.Fab")
		)
		(fp_line
			(start -0.12065 -0.305054)
			(end -0.12065 -0.2794)
			(stroke
				(width 0.1)
				(type default)
			)
			(layer "F.Fab")
		)
		(fp_line
			(start -0.12065 -0.2794)
			(end 0.12065 -0.2794)
			(stroke
				(width 0.1)
				(type default)
			)
			(layer "F.Fab")
		)
		(fp_line
			(start -0.12065 0.2794)
			(end -0.12065 0.3048)
			(stroke
				(width 0.1)
				(type default)
			)
			(layer "F.Fab")
		)
		(fp_line
			(start -0.12065 0.3048)
			(end -0.67945 0.3048)
			(stroke
				(width 0.1)
				(type default)
			)
			(layer "F.Fab")
		)
		(fp_line
			(start 0.120396 0.2794)
			(end -0.12065 0.2794)
			(stroke
				(width 0.1)
				(type default)
			)
			(layer "F.Fab")
		)
		(fp_line
			(start 0.120396 0.3048)
			(end 0.120396 0.2794)
			(stroke
				(width 0.1)
				(type default)
			)
			(layer "F.Fab")
		)
		(fp_line
			(start 0.12065 -0.3048)
			(end 0.67945 -0.3048)
			(stroke
				(width 0.1)
				(type default)
			)
			(layer "F.Fab")
		)
		(fp_line
			(start 0.12065 -0.2794)
			(end 0.12065 -0.3048)
			(stroke
				(width 0.1)
				(type default)
			)
			(layer "F.Fab")
		)
		(fp_line
			(start 0.67945 -0.3048)
			(end 0.67945 0.3048)
			(stroke
				(width 0.1)
				(type default)
			)
			(layer "F.Fab")
		)
		(fp_line
			(start 0.67945 0.3048)
			(end 0.120396 0.3048)
			(stroke
				(width 0.1)
				(type default)
			)
			(layer "F.Fab")
		)
		(pad "1" smd circle
			(at -0.40005 0)
			(size 0 0)
			(layers "F.Cu" "F.Mask" "F.Paste")
			(net "P3V3_AUX")
		)
		(pad "2" smd circle
			(at 0.40005 0)
			(size 0 0)
			(layers "F.Cu" "F.Mask" "F.Paste")
			(net "GND")
		)
	)
	(footprint ""
		(layer "F.Cu")
		(at 41.5544 -389.8392 180)
		(property "Reference" "R6709"
			(at 0 0 180)
			(layer "F.SilkS")
			(hide yes)
			(effects
				(font
					(size 1.27 1.27)
				)
			)
		)
		(property "Value" ""
			(at 0 0 180)
			(layer "F.Fab")
			(effects
				(font
					(size 1.27 1.27)
				)
			)
		)
		(duplicate_pad_numbers_are_jumpers no)
		(fp_line
			(start 0.32512 0.175006)
			(end -0.32512 0.175006)
			(stroke
				(width 0.1)
				(type default)
			)
			(layer "F.Fab")
		)
		(fp_line
			(start 0.32512 -0.175006)
			(end 0.32512 0.175006)
			(stroke
				(width 0.1)
				(type default)
			)
			(layer "F.Fab")
		)
		(fp_line
			(start -0.32512 0.175006)
			(end -0.32512 -0.175006)
			(stroke
				(width 0.1)
				(type default)
			)
			(layer "F.Fab")
		)
		(fp_line
			(start -0.32512 -0.175006)
			(end 0.32512 -0.175006)
			(stroke
				(width 0.1)
				(type default)
			)
			(layer "F.Fab")
		)
		(pad "1" smd rect
			(at -0.2667 0 180)
			(size 0.3048 0.381)
			(layers "F.Cu" "F.Mask" "F.Paste")
			(net "RST_RT_CPU1_P0_RESET_N")
		)
		(pad "2" smd rect
			(at 0.2667 0)
			(size 0.3048 0.381)
			(layers "F.Cu" "F.Mask" "F.Paste")
			(net "RST_RT_CPU1_P0_RESET_R_N")
		)
	)
	(footprint ""
		(layer "F.Cu")
		(at 449.561712 -423.413936)
		(property "Reference" "PC6607"
			(at 0 0 0)
			(layer "F.SilkS")
			(hide yes)
			(effects
				(font
					(size 1.27 1.27)
				)
			)
		)
		(property "Value" ""
			(at 0 0 0)
			(layer "F.Fab")
			(effects
				(font
					(size 1.27 1.27)
				)
			)
		)
		(duplicate_pad_numbers_are_jumpers no)
		(fp_line
			(start -0.7874 -0.4064)
			(end 0.7874 -0.4064)
			(stroke
				(width 0.1524)
				(type default)
			)
			(layer "F.SilkS")
		)
		(fp_line
			(start -0.7874 0.4064)
			(end -0.7874 -0.4064)
			(stroke
				(width 0.1524)
				(type default)
			)
			(layer "F.SilkS")
		)
		(fp_line
			(start 0.7874 -0.4064)
			(end 0.7874 0.4064)
			(stroke
				(width 0.1524)
				(type default)
			)
			(layer "F.SilkS")
		)
		(fp_line
			(start 0.7874 0.4064)
			(end -0.7874 0.4064)
			(stroke
				(width 0.1524)
				(type default)
			)
			(layer "F.SilkS")
		)
		(fp_line
			(start -0.67945 -0.305054)
			(end -0.12065 -0.305054)
			(stroke
				(width 0.1)
				(type default)
			)
			(layer "F.Fab")
		)
		(fp_line
			(start -0.67945 0.3048)
			(end -0.67945 -0.305054)
			(stroke
				(width 0.1)
				(type default)
			)
			(layer "F.Fab")
		)
		(fp_line
			(start -0.12065 -0.305054)
			(end -0.12065 -0.2794)
			(stroke
				(width 0.1)
				(type default)
			)
			(layer "F.Fab")
		)
		(fp_line
			(start -0.12065 -0.2794)
			(end 0.12065 -0.2794)
			(stroke
				(width 0.1)
				(type default)
			)
			(layer "F.Fab")
		)
		(fp_line
			(start -0.12065 0.2794)
			(end -0.12065 0.3048)
			(stroke
				(width 0.1)
				(type default)
			)
			(layer "F.Fab")
		)
		(fp_line
			(start -0.12065 0.3048)
			(end -0.67945 0.3048)
			(stroke
				(width 0.1)
				(type default)
			)
			(layer "F.Fab")
		)
		(fp_line
			(start 0.120396 0.2794)
			(end -0.12065 0.2794)
			(stroke
				(width 0.1)
				(type default)
			)
			(layer "F.Fab")
		)
		(fp_line
			(start 0.120396 0.3048)
			(end 0.120396 0.2794)
			(stroke
				(width 0.1)
				(type default)
			)
			(layer "F.Fab")
		)
		(fp_line
			(start 0.12065 -0.3048)
			(end 0.67945 -0.3048)
			(stroke
				(width 0.1)
				(type default)
			)
			(layer "F.Fab")
		)
		(fp_line
			(start 0.12065 -0.2794)
			(end 0.12065 -0.3048)
			(stroke
				(width 0.1)
				(type default)
			)
			(layer "F.Fab")
		)
		(fp_line
			(start 0.67945 -0.3048)
			(end 0.67945 0.3048)
			(stroke
				(width 0.1)
				(type default)
			)
			(layer "F.Fab")
		)
		(fp_line
			(start 0.67945 0.3048)
			(end 0.120396 0.3048)
			(stroke
				(width 0.1)
				(type default)
			)
			(layer "F.Fab")
		)
		(pad "1" smd circle
			(at -0.40005 0)
			(size 0 0)
			(layers "F.Cu" "F.Mask" "F.Paste")
			(net "P0V9_RETIMER_CPU0_TEMP0")
		)
		(pad "2" smd circle
			(at 0.40005 0)
			(size 0 0)
			(layers "F.Cu" "F.Mask" "F.Paste")
			(net "GND")
		)
	)
)
